# S9S_MB_2U (Grand Teton) — schematic netlist excerpt (pin names and nets, part order shuffled) for the footprints in the layout excerpt that follows; sources: Cadence DE-HDL packaged netlist, KiCad conversion of 03242023_DA0F0TMBIJ0_F0T_Motherboard_J_brd_V01_OCP.brd

PC2169  Q_CAP  1UF 25V 10% EMPTY  pkg C0402  page 163 : A = P3V3_AUX ; B = GND
PC5328  Q_CAP  1UF 25V 10% X6S  pkg C0402  page 156 : A = P3V3_AUX ; B = GND

(kicad_pcb
	(version 20260206)
	(generator "pcbnew")
	(generator_version "10.0")
	(general
		(thickness 1.6)
		(legacy_teardrops no)
	)
	(paper "A4")
	(title_block
		(title "03242023_DA0F0TMBIJ0_F0T_Motherboard_J_brd_V01_OCP.brd")
		(comment 1 "Grand Teton / footprints 1050-1051 of 6105")
	)
	(layers
		(0 "F.Cu" signal "TOP")
		(4 "In1.Cu" signal "GND")
		(6 "In2.Cu" signal "IN1")
		(8 "In3.Cu" signal "GND1")
		(10 "In4.Cu" signal "IN2")
		(12 "In5.Cu" signal "GND2")
		(14 "In6.Cu" signal "IN3")
		(16 "In7.Cu" signal "GND3")
		(18 "In8.Cu" signal "VCC")
		(20 "In9.Cu" signal "VCC1")
		(22 "In10.Cu" signal "GND4")
		(24 "In11.Cu" signal "IN4")
		(26 "In12.Cu" signal "GND5")
		(28 "In13.Cu" signal "IN5")
		(30 "In14.Cu" signal "GND6")
		(32 "In15.Cu" signal "IN6")
		(34 "In16.Cu" signal "GND7")
		(2 "B.Cu" signal "BOTTOM")
		(9 "F.Adhes" user "F.Adhesive")
		(11 "B.Adhes" user "B.Adhesive")
		(13 "F.Paste" user "Package Geometry/Pastemask Top")
		(15 "B.Paste" user "Package Geometry/Pastemask Bottom")
		(5 "F.SilkS" user "Ref Des/Silkscreen Top")
		(7 "B.SilkS" user "Ref Des/Silkscreen Bottom")
		(1 "F.Mask" user "Board Geometry/Soldermask Top")
		(3 "B.Mask" user "Board Geometry/Soldermask Bottom")
		(17 "Dwgs.User" user "User.Drawings")
		(19 "Cmts.User" user "User.Comments")
		(21 "Eco1.User" user "User.Eco1")
		(23 "Eco2.User" user "User.Eco2")
		(25 "Edge.Cuts" user "Board Geometry/Outline")
		(27 "Margin" user)
		(31 "F.CrtYd" user "Package Geometry/Place Bound Top")
		(29 "B.CrtYd" user "Package Geometry/Place Bound Bottom")
		(35 "F.Fab" user "Ref Des/Assembly Top")
		(33 "B.Fab" user "Ref Des/Assembly Bottom")
	)
	(footprint ""
		(layer "F.Cu")
		(at 66.94932 -56.540908 -90)
		(property "Reference" "PC2169"
			(at 0 0 270)
			(layer "F.SilkS")
			(hide yes)
			(effects
				(font
					(size 1.27 1.27)
				)
			)
		)
		(property "Value" ""
			(at 0 0 270)
			(layer "F.Fab")
			(effects
				(font
					(size 1.27 1.27)
				)
			)
		)
		(duplicate_pad_numbers_are_jumpers no)
		(fp_line
			(start -0.7874 0.4064)
			(end -0.7874 -0.4064)
			(stroke
				(width 0.1524)
				(type default)
			)
			(layer "F.SilkS")
		)
		(fp_line
			(start 0.7874 0.4064)
			(end -0.7874 0.4064)
			(stroke
				(width 0.1524)
				(type default)
			)
			(layer "F.SilkS")
		)
		(fp_line
			(start -0.7874 -0.4064)
			(end 0.7874 -0.4064)
			(stroke
				(width 0.1524)
				(type default)
			)
			(layer "F.SilkS")
		)
		(fp_line
			(start 0.7874 -0.4064)
			(end 0.7874 0.4064)
			(stroke
				(width 0.1524)
				(type default)
			)
			(layer "F.SilkS")
		)
		(fp_line
			(start -0.67945 0.3048)
			(end -0.67945 -0.305054)
			(stroke
				(width 0.1)
				(type default)
			)
			(layer "F.Fab")
		)
		(fp_line
			(start -0.12065 0.3048)
			(end -0.67945 0.3048)
			(stroke
				(width 0.1)
				(type default)
			)
			(layer "F.Fab")
		)
		(fp_line
			(start 0.120396 0.3048)
			(end 0.120396 0.2794)
			(stroke
				(width 0.1)
				(type default)
			)
			(layer "F.Fab")
		)
		(fp_line
			(start 0.67945 0.3048)
			(end 0.120396 0.3048)
			(stroke
				(width 0.1)
				(type default)
			)
			(layer "F.Fab")
		)
		(fp_line
			(start -0.12065 0.2794)
			(end -0.12065 0.3048)
			(stroke
				(width 0.1)
				(type default)
			)
			(layer "F.Fab")
		)
		(fp_line
			(start 0.120396 0.2794)
			(end -0.12065 0.2794)
			(stroke
				(width 0.1)
				(type default)
			)
			(layer "F.Fab")
		)
		(fp_line
			(start -0.12065 -0.2794)
			(end 0.12065 -0.2794)
			(stroke
				(width 0.1)
				(type default)
			)
			(layer "F.Fab")
		)
		(fp_line
			(start 0.12065 -0.2794)
			(end 0.12065 -0.3048)
			(stroke
				(width 0.1)
				(type default)
			)
			(layer "F.Fab")
		)
		(fp_line
			(start 0.12065 -0.3048)
			(end 0.67945 -0.3048)
			(stroke
				(width 0.1)
				(type default)
			)
			(layer "F.Fab")
		)
		(fp_line
			(start 0.67945 -0.3048)
			(end 0.67945 0.3048)
			(stroke
				(width 0.1)
				(type default)
			)
			(layer "F.Fab")
		)
		(fp_line
			(start -0.67945 -0.305054)
			(end -0.12065 -0.305054)
			(stroke
				(width 0.1)
				(type default)
			)
			(layer "F.Fab")
		)
		(fp_line
			(start -0.12065 -0.305054)
			(end -0.12065 -0.2794)
			(stroke
				(width 0.1)
				(type default)
			)
			(layer "F.Fab")
		)
		(pad "1" smd circle
			(at -0.40005 0 270)
			(size 0 0)
			(layers "F.Cu" "F.Mask" "F.Paste")
			(net "P3V3_AUX")
		)
		(pad "2" smd circle
			(at 0.40005 0 270)
			(size 0 0)
			(layers "F.Cu" "F.Mask" "F.Paste")
			(net "GND")
		)
	)
	(footprint ""
		(layer "F.Cu")
		(at 435.997858 -107.78236 180)
		(property "Reference" "PC5328"
			(at 0 0 180)
			(layer "F.SilkS")
			(hide yes)
			(effects
				(font
					(size 1.27 1.27)
				)
			)
		)
		(property "Value" ""
			(at 0 0 180)
			(layer "F.Fab")
			(effects
				(font
					(size 1.27 1.27)
				)
			)
		)
		(duplicate_pad_numbers_are_jumpers no)
		(fp_line
			(start 0.7874 0.4064)
			(end -0.7874 0.4064)
			(stroke
				(width 0.1524)
				(type default)
			)
			(layer "F.SilkS")
		)
		(fp_line
			(start 0.7874 -0.4064)
			(end 0.7874 0.4064)
			(stroke
				(width 0.1524)
				(type default)
			)
			(layer "F.SilkS")
		)
		(fp_line
			(start -0.7874 0.4064)
			(end -0.7874 -0.4064)
			(stroke
				(width 0.1524)
				(type default)
			)
			(layer "F.SilkS")
		)
		(fp_line
			(start -0.7874 -0.4064)
			(end 0.7874 -0.4064)
			(stroke
				(width 0.1524)
				(type default)
			)
			(layer "F.SilkS")
		)
		(fp_line
			(start 0.67945 0.3048)
			(end 0.120396 0.3048)
			(stroke
				(width 0.1)
				(type default)
			)
			(layer "F.Fab")
		)
		(fp_line
			(start 0.67945 -0.3048)
			(end 0.67945 0.3048)
			(stroke
				(width 0.1)
				(type default)
			)
			(layer "F.Fab")
		)
		(fp_line
			(start 0.12065 -0.2794)
			(end 0.12065 -0.3048)
			(stroke
				(width 0.1)
				(type default)
			)
			(layer "F.Fab")
		)
		(fp_line
			(start 0.12065 -0.3048)
			(end 0.67945 -0.3048)
			(stroke
				(width 0.1)
				(type default)
			)
			(layer "F.Fab")
		)
		(fp_line
			(start 0.120396 0.3048)
			(end 0.120396 0.2794)
			(stroke
				(width 0.1)
				(type default)
			)
			(layer "F.Fab")
		)
		(fp_line
			(start 0.120396 0.2794)
			(end -0.12065 0.2794)
			(stroke
				(width 0.1)
				(type default)
			)
			(layer "F.Fab")
		)
		(fp_line
			(start -0.12065 0.3048)
			(end -0.67945 0.3048)
			(stroke
				(width 0.1)
				(type default)
			)
			(layer "F.Fab")
		)
		(fp_line
			(start -0.12065 0.2794)
			(end -0.12065 0.3048)
			(stroke
				(width 0.1)
				(type default)
			)
			(layer "F.Fab")
		)
		(fp_line
			(start -0.12065 -0.2794)
			(end 0.12065 -0.2794)
			(stroke
				(width 0.1)
				(type default)
			)
			(layer "F.Fab")
		)
		(fp_line
			(start -0.12065 -0.305054)
			(end -0.12065 -0.2794)
			(stroke
				(width 0.1)
				(type default)
			)
			(layer "F.Fab")
		)
		(fp_line
			(start -0.67945 0.3048)
			(end -0.67945 -0.305054)
			(stroke
				(width 0.1)
				(type default)
			)
			(layer "F.Fab")
		)
		(fp_line
			(start -0.67945 -0.305054)
			(end -0.12065 -0.305054)
			(stroke
				(width 0.1)
				(type default)
			)
			(layer "F.Fab")
		)
		(pad "1" smd circle
			(at -0.40005 0 180)
			(size 0 0)
			(layers "F.Cu" "F.Mask" "F.Paste")
			(net "P3V3_AUX")
		)
		(pad "2" smd circle
			(at 0.40005 0 180)
			(size 0 0)
			(layers "F.Cu" "F.Mask" "F.Paste")
			(net "GND")
		)
	)
)
